(kicad_pcb
	(version 20260206)
	(generator "pcbnew")
	(generator_version "10.0")
	(general
		(thickness 1.6)
		(legacy_teardrops no)
	)
	(paper "A4")
	(title_block
		(title "03242023_DA0F0TMBIJ0_F0T_Motherboard_J_brd_V01_OCP.brd")
		(comment 1 "Grand Teton / footprints 5584-5589 of 6105")
	)
	(layers
		(0 "F.Cu" signal "TOP")
		(4 "In1.Cu" signal "GND")
		(6 "In2.Cu" signal "IN1")
		(8 "In3.Cu" signal "GND1")
		(10 "In4.Cu" signal "IN2")
		(12 "In5.Cu" signal "GND2")
		(14 "In6.Cu" signal "IN3")
		(16 "In7.Cu" signal "GND3")
		(18 "In8.Cu" signal "VCC")
		(20 "In9.Cu" signal "VCC1")
		(22 "In10.Cu" signal "GND4")
		(24 "In11.Cu" signal "IN4")
		(26 "In12.Cu" signal "GND5")
		(28 "In13.Cu" signal "IN5")
		(30 "In14.Cu" signal "GND6")
		(32 "In15.Cu" signal "IN6")
		(34 "In16.Cu" signal "GND7")
		(2 "B.Cu" signal "BOTTOM")
		(9 "F.Adhes" user "F.Adhesive")
		(11 "B.Adhes" user "B.Adhesive")
		(13 "F.Paste" user "Package Geometry/Pastemask Top")
		(15 "B.Paste" user "Package Geometry/Pastemask Bottom")
		(5 "F.SilkS" user "Ref Des/Silkscreen Top")
		(7 "B.SilkS" user "Ref Des/Silkscreen Bottom")
		(1 "F.Mask" user "Board Geometry/Soldermask Top")
		(3 "B.Mask" user "Board Geometry/Soldermask Bottom")
		(17 "Dwgs.User" user "User.Drawings")
		(19 "Cmts.User" user "User.Comments")
		(21 "Eco1.User" user "User.Eco1")
		(23 "Eco2.User" user "User.Eco2")
		(25 "Edge.Cuts" user "Board Geometry/Outline")
		(27 "Margin" user)
		(31 "F.CrtYd" user "Package Geometry/Place Bound Top")
		(29 "B.CrtYd" user "Package Geometry/Place Bound Bottom")
		(35 "F.Fab" user "Ref Des/Assembly Top")
		(33 "B.Fab" user "Ref Des/Assembly Bottom")
	)
	(footprint ""
		(layer "B.Cu")
		(at 180.26888 -123.154948 180)
		(property "Reference" "C1943"
			(at 0 0 0)
			(layer "B.SilkS")
			(hide yes)
			(effects
				(font
					(size 1.27 1.27)
				)
				(justify mirror)
			)
		)
		(property "Value" ""
			(at 0 0 0)
			(layer "B.Fab")
			(effects
				(font
					(size 1.27 1.27)
				)
				(justify mirror)
			)
		)
		(duplicate_pad_numbers_are_jumpers no)
		(fp_line
			(start 0.7874 0.4064)
			(end 0.7874 -0.4064)
			(stroke
				(width 0.1524)
				(type default)
			)
			(layer "B.SilkS")
		)
		(fp_line
			(start 0.7874 -0.4064)
			(end -0.7874 -0.4064)
			(stroke
				(width 0.1524)
				(type default)
			)
			(layer "B.SilkS")
		)
		(fp_line
			(start -0.7874 0.4064)
			(end 0.7874 0.4064)
			(stroke
				(width 0.1524)
				(type default)
			)
			(layer "B.SilkS")
		)
		(fp_line
			(start -0.7874 -0.4064)
			(end -0.7874 0.4064)
			(stroke
				(width 0.1524)
				(type default)
			)
			(layer "B.SilkS")
		)
		(fp_line
			(start 0.67945 0.3048)
			(end 0.67945 -0.305054)
			(stroke
				(width 0.1)
				(type default)
			)
			(layer "B.Fab")
		)
		(fp_line
			(start 0.67945 -0.305054)
			(end 0.12065 -0.305054)
			(stroke
				(width 0.1)
				(type default)
			)
			(layer "B.Fab")
		)
		(fp_line
			(start 0.12065 0.3048)
			(end 0.67945 0.3048)
			(stroke
				(width 0.1)
				(type default)
			)
			(layer "B.Fab")
		)
		(fp_line
			(start 0.12065 0.2794)
			(end 0.12065 0.3048)
			(stroke
				(width 0.1)
				(type default)
			)
			(layer "B.Fab")
		)
		(fp_line
			(start 0.12065 -0.2794)
			(end -0.12065 -0.2794)
			(stroke
				(width 0.1)
				(type default)
			)
			(layer "B.Fab")
		)
		(fp_line
			(start 0.12065 -0.305054)
			(end 0.12065 -0.2794)
			(stroke
				(width 0.1)
				(type default)
			)
			(layer "B.Fab")
		)
		(fp_line
			(start -0.120396 0.3048)
			(end -0.120396 0.2794)
			(stroke
				(width 0.1)
				(type default)
			)
			(layer "B.Fab")
		)
		(fp_line
			(start -0.120396 0.2794)
			(end 0.12065 0.2794)
			(stroke
				(width 0.1)
				(type default)
			)
			(layer "B.Fab")
		)
		(fp_line
			(start -0.12065 -0.2794)
			(end -0.12065 -0.3048)
			(stroke
				(width 0.1)
				(type default)
			)
			(layer "B.Fab")
		)
		(fp_line
			(start -0.12065 -0.3048)
			(end -0.67945 -0.3048)
			(stroke
				(width 0.1)
				(type default)
			)
			(layer "B.Fab")
		)
		(fp_line
			(start -0.67945 0.3048)
			(end -0.120396 0.3048)
			(stroke
				(width 0.1)
				(type default)
			)
			(layer "B.Fab")
		)
		(fp_line
			(start -0.67945 -0.3048)
			(end -0.67945 0.3048)
			(stroke
				(width 0.1)
				(type default)
			)
			(layer "B.Fab")
		)
		(pad "1" smd circle
			(at 0.40005 0)
			(size 0 0)
			(layers "B.Cu" "B.Mask" "B.Paste")
			(net "VCC_PLD_CORE")
		)
		(pad "2" smd circle
			(at -0.40005 0)
			(size 0 0)
			(layers "B.Cu" "B.Mask" "B.Paste")
			(net "GND")
		)
	)
	(footprint ""
		(layer "B.Cu")
		(at 177.355754 -115.775486 90)
		(property "Reference" "C1930"
			(at 0 0 90)
			(layer "B.SilkS")
			(hide yes)
			(effects
				(font
					(size 1.27 1.27)
				)
				(justify mirror)
			)
		)
		(property "Value" ""
			(at 0 0 90)
			(layer "B.Fab")
			(effects
				(font
					(size 1.27 1.27)
				)
				(justify mirror)
			)
		)
		(duplicate_pad_numbers_are_jumpers no)
		(fp_line
			(start 0.69215 -0.2921)
			(end -0.69215 -0.2921)
			(stroke
				(width 0.1524)
				(type default)
			)
			(layer "B.SilkS")
		)
		(fp_line
			(start -0.69215 -0.2921)
			(end -0.69215 0.2921)
			(stroke
				(width 0.1524)
				(type default)
			)
			(layer "B.SilkS")
		)
		(fp_line
			(start 0.69215 0.2921)
			(end 0.69215 -0.2921)
			(stroke
				(width 0.1524)
				(type default)
			)
			(layer "B.SilkS")
		)
		(fp_line
			(start -0.69215 0.2921)
			(end 0.69215 0.2921)
			(stroke
				(width 0.1524)
				(type default)
			)
			(layer "B.SilkS")
		)
		(fp_line
			(start 0.51435 -0.2794)
			(end -0.51435 -0.2794)
			(stroke
				(width 0.1)
				(type default)
			)
			(layer "B.Fab")
		)
		(fp_line
			(start -0.51435 -0.2794)
			(end -0.51435 0.2794)
			(stroke
				(width 0.1)
				(type default)
			)
			(layer "B.Fab")
		)
		(fp_line
			(start 0.51435 0.2794)
			(end 0.51435 -0.2794)
			(stroke
				(width 0.1)
				(type default)
			)
			(layer "B.Fab")
		)
		(fp_line
			(start -0.51435 0.2794)
			(end 0.51435 0.2794)
			(stroke
				(width 0.1)
				(type default)
			)
			(layer "B.Fab")
		)
		(pad "1" smd circle
			(at 0.40005 0 270)
			(size 0 0)
			(layers "B.Cu" "B.Mask" "B.Paste")
			(net "P3V3_AUX_FPGA_VCCIO1")
		)
		(pad "2" smd circle
			(at -0.40005 0 270)
			(size 0 0)
			(layers "B.Cu" "B.Mask" "B.Paste")
			(net "GND")
		)
		(zone
			(layer "B.Cu")
			(hatch none 0.5)
			(connect_pads
				(clearance 0)
			)
			(min_thickness 0.25)
			(keepout
				(tracks not_allowed)
				(vias allowed)
				(pads allowed)
				(copperpour not_allowed)
				(footprints allowed)
			)
			(placement
				(enabled no)
				(sheetname "")
			)
			(fill
				(thermal_gap 0.5)
				(thermal_bridge_width 0.5)
				(island_removal_mode 0)
			)
			(polygon
				(pts
					(xy 177.443384 -115.965986) (xy 177.50155 -115.874546) (xy 177.50155 -115.675156) (xy 177.443384 -115.584986)
					(xy 177.268124 -115.584986) (xy 177.209704 -115.675156) (xy 177.209704 -115.874546) (xy 177.26787 -115.965986)
				)
			)
		)
	)
	(footprint ""
		(layer "B.Cu")
		(at 317.56604 -193.53911 90)
		(property "Reference" "R344"
			(at 0 0 90)
			(layer "B.SilkS")
			(hide yes)
			(effects
				(font
					(size 1.27 1.27)
				)
				(justify mirror)
			)
		)
		(property "Value" ""
			(at 0 0 90)
			(layer "B.Fab")
			(effects
				(font
					(size 1.27 1.27)
				)
				(justify mirror)
			)
		)
		(duplicate_pad_numbers_are_jumpers no)
		(fp_line
			(start 0.7874 -0.4064)
			(end -0.7874 -0.4064)
			(stroke
				(width 0.1524)
				(type default)
			)
			(layer "B.SilkS")
		)
		(fp_line
			(start -0.7874 -0.4064)
			(end -0.7874 0.4064)
			(stroke
				(width 0.1524)
				(type default)
			)
			(layer "B.SilkS")
		)
		(fp_line
			(start 0.7874 0.4064)
			(end 0.7874 -0.4064)
			(stroke
				(width 0.1524)
				(type default)
			)
			(layer "B.SilkS")
		)
		(fp_line
			(start -0.7874 0.4064)
			(end 0.7874 0.4064)
			(stroke
				(width 0.1524)
				(type default)
			)
			(layer "B.SilkS")
		)
		(fp_line
			(start 0.67945 -0.305054)
			(end 0.12065 -0.305054)
			(stroke
				(width 0.1)
				(type default)
			)
			(layer "B.Fab")
		)
		(fp_line
			(start 0.12065 -0.305054)
			(end 0.12065 -0.2794)
			(stroke
				(width 0.1)
				(type default)
			)
			(layer "B.Fab")
		)
		(fp_line
			(start -0.12065 -0.3048)
			(end -0.67945 -0.3048)
			(stroke
				(width 0.1)
				(type default)
			)
			(layer "B.Fab")
		)
		(fp_line
			(start -0.67945 -0.3048)
			(end -0.67945 0.3048)
			(stroke
				(width 0.1)
				(type default)
			)
			(layer "B.Fab")
		)
		(fp_line
			(start 0.12065 -0.2794)
			(end -0.12065 -0.2794)
			(stroke
				(width 0.1)
				(type default)
			)
			(layer "B.Fab")
		)
		(fp_line
			(start -0.12065 -0.2794)
			(end -0.12065 -0.3048)
			(stroke
				(width 0.1)
				(type default)
			)
			(layer "B.Fab")
		)
		(fp_line
			(start 0.12065 0.2794)
			(end 0.12065 0.3048)
			(stroke
				(width 0.1)
				(type default)
			)
			(layer "B.Fab")
		)
		(fp_line
			(start -0.120396 0.2794)
			(end 0.12065 0.2794)
			(stroke
				(width 0.1)
				(type default)
			)
			(layer "B.Fab")
		)
		(fp_line
			(start 0.67945 0.3048)
			(end 0.67945 -0.305054)
			(stroke
				(width 0.1)
				(type default)
			)
			(layer "B.Fab")
		)
		(fp_line
			(start 0.12065 0.3048)
			(end 0.67945 0.3048)
			(stroke
				(width 0.1)
				(type default)
			)
			(layer "B.Fab")
		)
		(fp_line
			(start -0.120396 0.3048)
			(end -0.120396 0.2794)
			(stroke
				(width 0.1)
				(type default)
			)
			(layer "B.Fab")
		)
		(fp_line
			(start -0.67945 0.3048)
			(end -0.120396 0.3048)
			(stroke
				(width 0.1)
				(type default)
			)
			(layer "B.Fab")
		)
		(pad "1" smd circle
			(at 0.40005 0 270)
			(size 0 0)
			(layers "B.Cu" "B.Mask" "B.Paste")
			(net "H_CPU0_ERR2_LVC1_R_N")
		)
		(pad "2" smd circle
			(at -0.40005 0 270)
			(size 0 0)
			(layers "B.Cu" "B.Mask" "B.Paste")
			(net "H_CPU_ERR2_LVC1_R_N")
		)
	)
	(footprint ""
		(layer "B.Cu")
		(at 302.35144 -47.137828 180)
		(property "Reference" "C1198"
			(at 0 0 0)
			(layer "B.SilkS")
			(hide yes)
			(effects
				(font
					(size 1.27 1.27)
				)
				(justify mirror)
			)
		)
		(property "Value" ""
			(at 0 0 0)
			(layer "B.Fab")
			(effects
				(font
					(size 1.27 1.27)
				)
				(justify mirror)
			)
		)
		(duplicate_pad_numbers_are_jumpers no)
		(fp_line
			(start 1.2954 0.5842)
			(end 1.2954 -0.5842)
			(stroke
				(width 0.1524)
				(type default)
			)
			(layer "B.SilkS")
		)
		(fp_line
			(start 1.2954 -0.5842)
			(end -1.2954 -0.5842)
			(stroke
				(width 0.1524)
				(type default)
			)
			(layer "B.SilkS")
		)
		(fp_line
			(start 0 -0.5842)
			(end 0 0.5842)
			(stroke
				(width 0.1524)
				(type default)
			)
			(layer "B.SilkS")
		)
		(fp_line
			(start -1.2954 0.5842)
			(end 1.2954 0.5842)
			(stroke
				(width 0.1524)
				(type default)
			)
			(layer "B.SilkS")
		)
		(fp_line
			(start -1.2954 -0.5842)
			(end -1.2954 0.5842)
			(stroke
				(width 0.1524)
				(type default)
			)
			(layer "B.SilkS")
		)
		(fp_line
			(start 1.1938 0.4064)
			(end 1.1938 -0.4064)
			(stroke
				(width 0.1)
				(type default)
			)
			(layer "B.Fab")
		)
		(fp_line
			(start 1.1938 -0.4064)
			(end 0.8636 -0.4064)
			(stroke
				(width 0.1)
				(type default)
			)
			(layer "B.Fab")
		)
		(fp_line
			(start 0.8636 0.4572)
			(end 0.8636 0.4064)
			(stroke
				(width 0.1)
				(type default)
			)
			(layer "B.Fab")
		)
		(fp_line
			(start 0.8636 0.4064)
			(end 1.1938 0.4064)
			(stroke
				(width 0.1)
				(type default)
			)
			(layer "B.Fab")
		)
		(fp_line
			(start 0.8636 -0.4064)
			(end 0.8636 -0.4572)
			(stroke
				(width 0.1)
				(type default)
			)
			(layer "B.Fab")
		)
		(fp_line
			(start 0.8636 -0.4572)
			(end -0.8636 -0.4572)
			(stroke
				(width 0.1)
				(type default)
			)
			(layer "B.Fab")
		)
		(fp_line
			(start -0.8636 0.4572)
			(end 0.8636 0.4572)
			(stroke
				(width 0.1)
				(type default)
			)
			(layer "B.Fab")
		)
		(fp_line
			(start -0.8636 0.4064)
			(end -0.8636 0.4572)
			(stroke
				(width 0.1)
				(type default)
			)
			(layer "B.Fab")
		)
		(fp_line
			(start -0.8636 -0.4064)
			(end -1.1938 -0.4064)
			(stroke
				(width 0.1)
				(type default)
			)
			(layer "B.Fab")
		)
		(fp_line
			(start -0.8636 -0.4572)
			(end -0.8636 -0.4064)
			(stroke
				(width 0.1)
				(type default)
			)
			(layer "B.Fab")
		)
		(fp_line
			(start -1.1938 0.4064)
			(end -0.8636 0.4064)
			(stroke
				(width 0.1)
				(type default)
			)
			(layer "B.Fab")
		)
		(fp_line
			(start -1.1938 -0.4064)
			(end -1.1938 0.4064)
			(stroke
				(width 0.1)
				(type default)
			)
			(layer "B.Fab")
		)
		(pad "1" smd rect
			(at 0.7366 0 90)
			(size 0.7112 0.8128)
			(layers "B.Cu" "B.Mask" "B.Paste")
			(net "P1V05_PCH_AUX")
		)
		(pad "2" smd rect
			(at -0.7366 0 90)
			(size 0.7112 0.8128)
			(layers "B.Cu" "B.Mask" "B.Paste")
			(net "GND")
		)
	)
	(footprint ""
		(layer "B.Cu")
		(at 114.822224 -337.607402 -90)
		(property "Reference" "PC538_P1_3"
			(at 0 0 90)
			(layer "B.SilkS")
			(hide yes)
			(effects
				(font
					(size 1.27 1.27)
				)
				(justify mirror)
			)
		)
		(property "Value" ""
			(at 0 0 90)
			(layer "B.Fab")
			(effects
				(font
					(size 1.27 1.27)
				)
				(justify mirror)
			)
		)
		(duplicate_pad_numbers_are_jumpers no)
		(fp_line
			(start -1.524 0.762)
			(end 1.524 0.762)
			(stroke
				(width 0.1524)
				(type default)
			)
			(layer "B.SilkS")
		)
		(fp_line
			(start 1.524 0.762)
			(end 1.524 -0.762)
			(stroke
				(width 0.1524)
				(type default)
			)
			(layer "B.SilkS")
		)
		(fp_line
			(start -1.524 -0.762)
			(end -1.524 0.762)
			(stroke
				(width 0.1524)
				(type default)
			)
			(layer "B.SilkS")
		)
		(fp_line
			(start 1.524 -0.762)
			(end -1.524 -0.762)
			(stroke
				(width 0.1524)
				(type default)
			)
			(layer "B.SilkS")
		)
		(fp_line
			(start -1.1049 0.724916)
			(end -1.1049 -0.724916)
			(stroke
				(width 0.1)
				(type default)
			)
			(layer "B.Fab")
		)
		(fp_line
			(start 1.1049 0.724916)
			(end -1.1049 0.724916)
			(stroke
				(width 0.1)
				(type default)
			)
			(layer "B.Fab")
		)
		(fp_line
			(start -1.1049 -0.724916)
			(end 1.1049 -0.724916)
			(stroke
				(width 0.1)
				(type default)
			)
			(layer "B.Fab")
		)
		(fp_line
			(start 1.1049 -0.724916)
			(end 1.1049 0.724916)
			(stroke
				(width 0.1)
				(type default)
			)
			(layer "B.Fab")
		)
		(pad "1" smd rect
			(at 0.889 0 270)
			(size 1.016 1.27)
			(layers "B.Cu" "B.Mask" "B.Paste")
			(net "SW_P12V_PVCCIN_CPU1_FLT")
		)
		(pad "2" smd rect
			(at -0.889 0 270)
			(size 1.016 1.27)
			(layers "B.Cu" "B.Mask" "B.Paste")
			(net "GND")
		)
	)
	(footprint ""
		(layer "B.Cu")
		(at 426.892212 -122.57786 180)
		(property "Reference" "PR1380"
			(at 0 0 0)
			(layer "B.SilkS")
			(hide yes)
			(effects
				(font
					(size 1.27 1.27)
				)
				(justify mirror)
			)
		)
		(property "Value" ""
			(at 0 0 0)
			(layer "B.Fab")
			(effects
				(font
					(size 1.27 1.27)
				)
				(justify mirror)
			)
		)
		(duplicate_pad_numbers_are_jumpers no)
		(fp_line
			(start 0.7874 0.4064)
			(end 0.7874 -0.4064)
			(stroke
				(width 0.1524)
				(type default)
			)
			(layer "B.SilkS")
		)
		(fp_line
			(start 0.7874 -0.4064)
			(end -0.7874 -0.4064)
			(stroke
				(width 0.1524)
				(type default)
			)
			(layer "B.SilkS")
		)
		(fp_line
			(start -0.7874 0.4064)
			(end 0.7874 0.4064)
			(stroke
				(width 0.1524)
				(type default)
			)
			(layer "B.SilkS")
		)
		(fp_line
			(start -0.7874 -0.4064)
			(end -0.7874 0.4064)
			(stroke
				(width 0.1524)
				(type default)
			)
			(layer "B.SilkS")
		)
		(fp_line
			(start 0.67945 0.3048)
			(end 0.67945 -0.305054)
			(stroke
				(width 0.1)
				(type default)
			)
			(layer "B.Fab")
		)
		(fp_line
			(start 0.67945 -0.305054)
			(end 0.12065 -0.305054)
			(stroke
				(width 0.1)
				(type default)
			)
			(layer "B.Fab")
		)
		(fp_line
			(start 0.12065 0.3048)
			(end 0.67945 0.3048)
			(stroke
				(width 0.1)
				(type default)
			)
			(layer "B.Fab")
		)
		(fp_line
			(start 0.12065 0.2794)
			(end 0.12065 0.3048)
			(stroke
				(width 0.1)
				(type default)
			)
			(layer "B.Fab")
		)
		(fp_line
			(start 0.12065 -0.2794)
			(end -0.12065 -0.2794)
			(stroke
				(width 0.1)
				(type default)
			)
			(layer "B.Fab")
		)
		(fp_line
			(start 0.12065 -0.305054)
			(end 0.12065 -0.2794)
			(stroke
				(width 0.1)
				(type default)
			)
			(layer "B.Fab")
		)
		(fp_line
			(start -0.120396 0.3048)
			(end -0.120396 0.2794)
			(stroke
				(width 0.1)
				(type default)
			)
			(layer "B.Fab")
		)
		(fp_line
			(start -0.120396 0.2794)
			(end 0.12065 0.2794)
			(stroke
				(width 0.1)
				(type default)
			)
			(layer "B.Fab")
		)
		(fp_line
			(start -0.12065 -0.2794)
			(end -0.12065 -0.3048)
			(stroke
				(width 0.1)
				(type default)
			)
			(layer "B.Fab")
		)
		(fp_line
			(start -0.12065 -0.3048)
			(end -0.67945 -0.3048)
			(stroke
				(width 0.1)
				(type default)
			)
			(layer "B.Fab")
		)
		(fp_line
			(start -0.67945 0.3048)
			(end -0.120396 0.3048)
			(stroke
				(width 0.1)
				(type default)
			)
			(layer "B.Fab")
		)
		(fp_line
			(start -0.67945 -0.3048)
			(end -0.67945 0.3048)
			(stroke
				(width 0.1)
				(type default)
			)
			(layer "B.Fab")
		)
		(pad "1" smd circle
			(at 0.40005 0)
			(size 0 0)
			(layers "B.Cu" "B.Mask" "B.Paste")
			(net "P12V_AUX_CPU0_DIMM_ISEN_P")
		)
		(pad "2" smd circle
			(at -0.40005 0)
			(size 0 0)
			(layers "B.Cu" "B.Mask" "B.Paste")
			(net "PVCCD_HV_CPU0_ISENSE_P")
		)
	)
)
